(kicad_pcb
	(version 20260206)
	(generator "pcbnew")
	(generator_version "10.0")
	(general
		(thickness 1.6)
		(legacy_teardrops no)
	)
	(paper "A4")
	(title_block
		(title "baseboard — 13948-1b.1110WZS1818.brd")
		(comment 1 "Honey Badger (Wiwynn) / footprints 513-520 of 2523")
	)
	(layers
		(0 "F.Cu" signal "TOP")
		(4 "In1.Cu" signal "L2GND")
		(6 "In2.Cu" signal "L3")
		(8 "In3.Cu" signal "L4VCC")
		(10 "In4.Cu" signal "L5VCC")
		(12 "In5.Cu" signal "L6")
		(14 "In6.Cu" signal "L7GND")
		(2 "B.Cu" signal "BOTTOM")
		(9 "F.Adhes" user "F.Adhesive")
		(11 "B.Adhes" user "B.Adhesive")
		(13 "F.Paste" user "Package Geometry/Pastemask Top")
		(15 "B.Paste" user "Package Geometry/Pastemask Bottom")
		(5 "F.SilkS" user "Ref Des/Silkscreen Top")
		(7 "B.SilkS" user "Ref Des/Silkscreen Bottom")
		(1 "F.Mask" user "Board Geometry/Soldermask Top")
		(3 "B.Mask" user "Board Geometry/Soldermask Bottom")
		(17 "Dwgs.User" user "User.Drawings")
		(19 "Cmts.User" user "User.Comments")
		(21 "Eco1.User" user "User.Eco1")
		(23 "Eco2.User" user "User.Eco2")
		(25 "Edge.Cuts" user "Board Geometry/Outline")
		(27 "Margin" user)
		(31 "F.CrtYd" user "Package Geometry/Place Bound Top")
		(29 "B.CrtYd" user "Package Geometry/Place Bound Bottom")
		(35 "F.Fab" user "Ref Des/Assembly Top")
		(33 "B.Fab" user "Ref Des/Assembly Bottom")
	)
	(footprint ""
		(layer "F.Cu")
		(at 47.879 -219.837 -90)
		(property "Reference" "R2117"
			(at 0 0 270)
			(layer "F.SilkS")
			(hide yes)
			(effects
				(font
					(size 1.27 1.27)
				)
			)
		)
		(property "Value" "100KR2J-4-GP"
			(at -1.1811 -1.1303 270)
			(unlocked yes)
			(layer "F.Fab")
			(hide yes)
			(effects
				(font
					(size 1.016 1.016)
					(thickness 0.1524)
				)
			)
		)
		(property "Device Type" "R402H15"
			(at -1.1811 -2.6543 270)
			(unlocked yes)
			(layer "F.Fab")
			(hide yes)
			(effects
				(font
					(size 1.016 1.016)
					(thickness 0.1524)
				)
			)
		)
		(duplicate_pad_numbers_are_jumpers no)
		(fp_line
			(start -0.508 -0.9398)
			(end -0.508 0.9398)
			(stroke
				(width 0.1524)
				(type default)
			)
			(layer "F.SilkS")
		)
		(fp_line
			(start 0.508 -0.9398)
			(end -0.508 -0.9398)
			(stroke
				(width 0.1524)
				(type default)
			)
			(layer "F.SilkS")
		)
		(fp_rect
			(start -0.508 0.9398)
			(end 0.508 -0.9398)
			(stroke
				(width 0)
				(type default)
			)
			(fill no)
			(layer "F.CrtYd")
		)
		(fp_rect
			(start -0.508 0.9398)
			(end 0.508 -0.9398)
			(stroke
				(width 0)
				(type default)
			)
			(fill no)
			(layer "F.Fab")
		)
		(pad "1" smd custom
			(at 0 -0.4445 270)
			(size 0.1397 0.1397)
			(layers "F.Cu" "F.Mask" "F.Paste")
			(net "MB0_VCAP_R")
			(options
				(clearance outline)
				(anchor circle)
			)
			(primitives
				(gr_poly
					(pts
						(arc
							(start -0.1778 -0.2794)
							(mid -0.249642 -0.249642)
							(end -0.2794 -0.1778)
						)
						(arc
							(start -0.2794 0.1778)
							(mid -0.249642 0.249642)
							(end -0.1778 0.2794)
						)
						(arc
							(start 0.1778 0.2794)
							(mid 0.249642 0.249642)
							(end 0.2794 0.1778)
						)
						(arc
							(start 0.2794 -0.1778)
							(mid 0.249642 -0.249642)
							(end 0.1778 -0.2794)
						)
					)
					(width 0)
					(fill yes)
				)
			)
		)
		(pad "2" smd custom
			(at 0 0.4445 270)
			(size 0.1397 0.1397)
			(layers "F.Cu" "F.Mask" "F.Paste")
			(net "MB0_ISET_R")
			(options
				(clearance outline)
				(anchor circle)
			)
			(primitives
				(gr_poly
					(pts
						(arc
							(start -0.1778 -0.2794)
							(mid -0.249642 -0.249642)
							(end -0.2794 -0.1778)
						)
						(arc
							(start -0.2794 0.1778)
							(mid -0.249642 0.249642)
							(end -0.1778 0.2794)
						)
						(arc
							(start 0.1778 0.2794)
							(mid 0.249642 0.249642)
							(end 0.2794 0.1778)
						)
						(arc
							(start 0.2794 -0.1778)
							(mid 0.249642 -0.249642)
							(end 0.1778 -0.2794)
						)
					)
					(width 0)
					(fill yes)
				)
			)
		)
	)
	(footprint ""
		(layer "F.Cu")
		(at 197.485 -163.703 90)
		(property "Reference" "R576"
			(at 0 0 90)
			(layer "F.SilkS")
			(hide yes)
			(effects
				(font
					(size 1.27 1.27)
				)
			)
		)
		(property "Value" "1KR2J-1-GP"
			(at 0.064008 -3.993896 90)
			(unlocked yes)
			(layer "F.Fab")
			(hide yes)
			(effects
				(font
					(size 1.016 1.016)
					(thickness 0.1524)
				)
			)
		)
		(property "Device Type" "R402H16"
			(at 0.064008 -5.517896 90)
			(unlocked yes)
			(layer "F.Fab")
			(hide yes)
			(effects
				(font
					(size 1.016 1.016)
					(thickness 0.1524)
				)
			)
		)
		(duplicate_pad_numbers_are_jumpers no)
		(fp_line
			(start 0.508 -0.9398)
			(end -0.508 -0.9398)
			(stroke
				(width 0.1524)
				(type default)
			)
			(layer "F.SilkS")
		)
		(fp_line
			(start -0.508 -0.9398)
			(end -0.508 0.9398)
			(stroke
				(width 0.1524)
				(type default)
			)
			(layer "F.SilkS")
		)
		(fp_rect
			(start -0.508 0.9398)
			(end 0.508 -0.9398)
			(stroke
				(width 0)
				(type default)
			)
			(fill no)
			(layer "F.CrtYd")
		)
		(fp_rect
			(start -0.508 0.9398)
			(end 0.508 -0.9398)
			(stroke
				(width 0)
				(type default)
			)
			(fill no)
			(layer "F.Fab")
		)
		(pad "1" smd custom
			(at 0 -0.4445 90)
			(size 0.1397 0.1397)
			(layers "F.Cu" "F.Mask" "F.Paste")
			(net "P3V3_PG_R")
			(options
				(clearance outline)
				(anchor circle)
			)
			(primitives
				(gr_poly
					(pts
						(arc
							(start -0.1778 -0.2794)
							(mid -0.249642 -0.249642)
							(end -0.2794 -0.1778)
						)
						(arc
							(start -0.2794 0.1778)
							(mid -0.249642 0.249642)
							(end -0.1778 0.2794)
						)
						(arc
							(start 0.1778 0.2794)
							(mid 0.249642 0.249642)
							(end 0.2794 0.1778)
						)
						(arc
							(start 0.2794 -0.1778)
							(mid 0.249642 -0.249642)
							(end 0.1778 -0.2794)
						)
					)
					(width 0)
					(fill yes)
				)
			)
		)
		(pad "2" smd custom
			(at 0 0.4445 90)
			(size 0.1397 0.1397)
			(layers "F.Cu" "F.Mask" "F.Paste")
			(net "P3V3")
			(options
				(clearance outline)
				(anchor circle)
			)
			(primitives
				(gr_poly
					(pts
						(arc
							(start -0.1778 -0.2794)
							(mid -0.249642 -0.249642)
							(end -0.2794 -0.1778)
						)
						(arc
							(start -0.2794 0.1778)
							(mid -0.249642 0.249642)
							(end -0.1778 0.2794)
						)
						(arc
							(start 0.1778 0.2794)
							(mid 0.249642 0.249642)
							(end 0.2794 0.1778)
						)
						(arc
							(start 0.2794 -0.1778)
							(mid 0.249642 -0.249642)
							(end 0.1778 -0.2794)
						)
					)
					(width 0)
					(fill yes)
				)
			)
		)
	)
	(footprint ""
		(layer "F.Cu")
		(at 288.163 -210.49234 180)
		(property "Reference" "C172"
			(at 0 0 180)
			(layer "F.SilkS")
			(hide yes)
			(effects
				(font
					(size 1.27 1.27)
				)
			)
		)
		(property "Value" "SCD1U16V2KX-3GP"
			(at 1.1811 -2.7051 180)
			(unlocked yes)
			(layer "F.Fab")
			(hide yes)
			(effects
				(font
					(size 1.016 1.016)
					(thickness 0.1524)
				)
			)
		)
		(property "Device Type" "C402H22"
			(at 1.1811 -4.2291 180)
			(unlocked yes)
			(layer "F.Fab")
			(hide yes)
			(effects
				(font
					(size 1.016 1.016)
					(thickness 0.1524)
				)
			)
		)
		(duplicate_pad_numbers_are_jumpers no)
		(fp_rect
			(start -0.4318 0.9525)
			(end 0.4318 -0.9525)
			(stroke
				(width 0)
				(type default)
			)
			(fill no)
			(layer "F.CrtYd")
		)
		(fp_rect
			(start -0.4318 0.9525)
			(end 0.4318 -0.9525)
			(stroke
				(width 0)
				(type default)
			)
			(fill no)
			(layer "F.Fab")
		)
		(pad "1" smd custom
			(at 0 -0.4445 180)
			(size 0.1524 0.1524)
			(layers "F.Cu" "F.Mask" "F.Paste")
			(net "P1V53_STBY")
			(options
				(clearance outline)
				(anchor circle)
			)
			(primitives
				(gr_poly
					(pts
						(arc
							(start 0.3048 -0.2032)
							(mid 0.275042 -0.275042)
							(end 0.2032 -0.3048)
						)
						(arc
							(start -0.2032 -0.3048)
							(mid -0.275042 -0.275042)
							(end -0.3048 -0.2032)
						)
						(arc
							(start -0.3048 0.2032)
							(mid -0.275042 0.275042)
							(end -0.2032 0.3048)
						)
						(arc
							(start 0.2032 0.3048)
							(mid 0.275042 0.275042)
							(end 0.3048 0.2032)
						)
					)
					(width 0)
					(fill yes)
				)
			)
		)
		(pad "2" smd custom
			(at 0 0.4445 180)
			(size 0.1524 0.1524)
			(layers "F.Cu" "F.Mask" "F.Paste")
			(net "GND")
			(options
				(clearance outline)
				(anchor circle)
			)
			(primitives
				(gr_poly
					(pts
						(arc
							(start 0.3048 -0.2032)
							(mid 0.275042 -0.275042)
							(end 0.2032 -0.3048)
						)
						(arc
							(start -0.2032 -0.3048)
							(mid -0.275042 -0.275042)
							(end -0.3048 -0.2032)
						)
						(arc
							(start -0.3048 0.2032)
							(mid -0.275042 0.275042)
							(end -0.2032 0.3048)
						)
						(arc
							(start 0.2032 0.3048)
							(mid 0.275042 0.275042)
							(end 0.3048 0.2032)
						)
					)
					(width 0)
					(fill yes)
				)
			)
		)
	)
	(footprint ""
		(layer "F.Cu")
		(at 40.513 -169.291 90)
		(property "Reference" "R473"
			(at 0 0 90)
			(layer "F.SilkS")
			(hide yes)
			(effects
				(font
					(size 1.27 1.27)
				)
			)
		)
		(property "Value" "22KR2F-GP"
			(at 0.064008 -3.993896 90)
			(unlocked yes)
			(layer "F.Fab")
			(hide yes)
			(effects
				(font
					(size 1.016 1.016)
					(thickness 0.1524)
				)
			)
		)
		(property "Device Type" "R402H16"
			(at 0.064008 -5.517896 90)
			(unlocked yes)
			(layer "F.Fab")
			(hide yes)
			(effects
				(font
					(size 1.016 1.016)
					(thickness 0.1524)
				)
			)
		)
		(duplicate_pad_numbers_are_jumpers no)
		(fp_line
			(start 0.508 -0.9398)
			(end -0.508 -0.9398)
			(stroke
				(width 0.1524)
				(type default)
			)
			(layer "F.SilkS")
		)
		(fp_line
			(start -0.508 -0.9398)
			(end -0.508 0.9398)
			(stroke
				(width 0.1524)
				(type default)
			)
			(layer "F.SilkS")
		)
		(fp_rect
			(start -0.508 0.9398)
			(end 0.508 -0.9398)
			(stroke
				(width 0)
				(type default)
			)
			(fill no)
			(layer "F.CrtYd")
		)
		(fp_rect
			(start -0.508 0.9398)
			(end 0.508 -0.9398)
			(stroke
				(width 0)
				(type default)
			)
			(fill no)
			(layer "F.Fab")
		)
		(pad "1" smd custom
			(at 0 -0.4445 90)
			(size 0.1397 0.1397)
			(layers "F.Cu" "F.Mask" "F.Paste")
			(net "P3V3_STBY")
			(options
				(clearance outline)
				(anchor circle)
			)
			(primitives
				(gr_poly
					(pts
						(arc
							(start -0.1778 -0.2794)
							(mid -0.249642 -0.249642)
							(end -0.2794 -0.1778)
						)
						(arc
							(start -0.2794 0.1778)
							(mid -0.249642 0.249642)
							(end -0.1778 0.2794)
						)
						(arc
							(start 0.1778 0.2794)
							(mid 0.249642 0.249642)
							(end 0.2794 0.1778)
						)
						(arc
							(start 0.2794 -0.1778)
							(mid 0.249642 -0.249642)
							(end 0.1778 -0.2794)
						)
					)
					(width 0)
					(fill yes)
				)
			)
		)
		(pad "2" smd custom
			(at 0 0.4445 90)
			(size 0.1397 0.1397)
			(layers "F.Cu" "F.Mask" "F.Paste")
			(net "FP_PWR_BTN_N")
			(options
				(clearance outline)
				(anchor circle)
			)
			(primitives
				(gr_poly
					(pts
						(arc
							(start -0.1778 -0.2794)
							(mid -0.249642 -0.249642)
							(end -0.2794 -0.1778)
						)
						(arc
							(start -0.2794 0.1778)
							(mid -0.249642 0.249642)
							(end -0.1778 0.2794)
						)
						(arc
							(start 0.1778 0.2794)
							(mid 0.249642 0.249642)
							(end 0.2794 0.1778)
						)
						(arc
							(start 0.2794 -0.1778)
							(mid 0.249642 -0.249642)
							(end 0.1778 -0.2794)
						)
					)
					(width 0)
					(fill yes)
				)
			)
		)
	)
	(footprint ""
		(layer "F.Cu")
		(at 318.008 -171.577 90)
		(property "Reference" "C188"
			(at 0 0 90)
			(layer "F.SilkS")
			(hide yes)
			(effects
				(font
					(size 1.27 1.27)
				)
			)
		)
		(property "Value" "SC1U10V3KX-4GP-U"
			(at 0 -2.8194 90)
			(unlocked yes)
			(layer "F.Fab")
			(hide yes)
			(effects
				(font
					(size 1.016 1.016)
					(thickness 0.1524)
				)
			)
		)
		(property "Device Type" "C603H36"
			(at 0 -4.3434 90)
			(unlocked yes)
			(layer "F.Fab")
			(hide yes)
			(effects
				(font
					(size 1.016 1.016)
					(thickness 0.1524)
				)
			)
		)
		(duplicate_pad_numbers_are_jumpers no)
		(fp_line
			(start 0.508 0)
			(end -0.508 0)
			(stroke
				(width 0.2032)
				(type default)
			)
			(layer "F.SilkS")
		)
		(fp_rect
			(start -0.5842 1.3335)
			(end 0.5842 -1.3335)
			(stroke
				(width 0)
				(type default)
			)
			(fill no)
			(layer "F.CrtYd")
		)
		(fp_rect
			(start -0.5842 1.3335)
			(end 0.5842 -1.3335)
			(stroke
				(width 0)
				(type default)
			)
			(fill no)
			(layer "F.Fab")
		)
		(pad "1" smd custom
			(at 0 -0.762 90)
			(size 0.2159 0.2159)
			(layers "F.Cu" "F.Mask" "F.Paste")
			(net "JTAG_BMC_TRST_N")
			(options
				(clearance outline)
				(anchor circle)
			)
			(primitives
				(gr_poly
					(pts
						(arc
							(start -0.3302 -0.4318)
							(mid -0.402042 -0.402042)
							(end -0.4318 -0.3302)
						)
						(arc
							(start -0.4318 0.3302)
							(mid -0.402042 0.402042)
							(end -0.3302 0.4318)
						)
						(arc
							(start 0.3302 0.4318)
							(mid 0.402042 0.402042)
							(end 0.4318 0.3302)
						)
						(arc
							(start 0.4318 -0.3302)
							(mid 0.402042 -0.402042)
							(end 0.3302 -0.4318)
						)
					)
					(width 0)
					(fill yes)
				)
			)
		)
		(pad "2" smd custom
			(at 0 0.762 90)
			(size 0.2159 0.2159)
			(layers "F.Cu" "F.Mask" "F.Paste")
			(net "GND")
			(options
				(clearance outline)
				(anchor circle)
			)
			(primitives
				(gr_poly
					(pts
						(arc
							(start -0.3302 -0.4318)
							(mid -0.402042 -0.402042)
							(end -0.4318 -0.3302)
						)
						(arc
							(start -0.4318 0.3302)
							(mid -0.402042 0.402042)
							(end -0.3302 0.4318)
						)
						(arc
							(start 0.3302 0.4318)
							(mid 0.402042 0.402042)
							(end 0.4318 0.3302)
						)
						(arc
							(start 0.4318 -0.3302)
							(mid 0.402042 -0.402042)
							(end 0.3302 -0.4318)
						)
					)
					(width 0)
					(fill yes)
				)
			)
		)
	)
	(footprint ""
		(layer "F.Cu")
		(at 306.451 -179.324)
		(property "Reference" "TP175"
			(at 0 0 0)
			(layer "F.SilkS")
			(hide yes)
			(effects
				(font
					(size 1.27 1.27)
				)
			)
		)
		(property "Value" "TPAD28"
			(at 0.0127 -1.8034 0)
			(unlocked yes)
			(layer "F.Fab")
			(hide yes)
			(effects
				(font
					(size 1.016 1.016)
					(thickness 0.1524)
				)
			)
		)
		(property "Device Type" "TPAD28"
			(at 0.0127 -3.3274 0)
			(unlocked yes)
			(layer "F.Fab")
			(hide yes)
			(effects
				(font
					(size 1.016 1.016)
					(thickness 0.1524)
				)
			)
		)
		(duplicate_pad_numbers_are_jumpers no)
		(fp_poly
			(pts
				(arc
					(start 0.3556 0)
					(mid -0.3556 0)
					(end 0.3556 0)
				)
			)
			(stroke
				(width 0)
				(type default)
			)
			(fill no)
			(layer "F.CrtYd")
		)
		(fp_poly
			(pts
				(arc
					(start 0.6096 0)
					(mid -0.6096 0)
					(end 0.6096 0)
				)
			)
			(stroke
				(width 0)
				(type default)
			)
			(fill no)
			(layer "F.Fab")
		)
		(pad "1" smd circle
			(at 0 0)
			(size 0.7112 0.7112)
			(layers "F.Cu" "F.Mask" "F.Paste")
			(net "TP_BMC_GPIOM0")
		)
	)
	(footprint ""
		(layer "F.Cu")
		(at 274.193 -170.561 90)
		(property "Reference" "R239"
			(at 0 0 90)
			(layer "F.SilkS")
			(hide yes)
			(effects
				(font
					(size 1.27 1.27)
				)
			)
		)
		(property "Value" "0R2J-2-GP"
			(at 0.064008 -3.993896 90)
			(unlocked yes)
			(layer "F.Fab")
			(hide yes)
			(effects
				(font
					(size 1.016 1.016)
					(thickness 0.1524)
				)
			)
		)
		(property "Device Type" "R402H16"
			(at 0.064008 -5.517896 90)
			(unlocked yes)
			(layer "F.Fab")
			(hide yes)
			(effects
				(font
					(size 1.016 1.016)
					(thickness 0.1524)
				)
			)
		)
		(duplicate_pad_numbers_are_jumpers no)
		(fp_line
			(start 0.508 -0.9398)
			(end -0.508 -0.9398)
			(stroke
				(width 0.1524)
				(type default)
			)
			(layer "F.SilkS")
		)
		(fp_line
			(start -0.508 -0.9398)
			(end -0.508 0.9398)
			(stroke
				(width 0.1524)
				(type default)
			)
			(layer "F.SilkS")
		)
		(fp_rect
			(start -0.508 0.9398)
			(end 0.508 -0.9398)
			(stroke
				(width 0)
				(type default)
			)
			(fill no)
			(layer "F.CrtYd")
		)
		(fp_rect
			(start -0.508 0.9398)
			(end 0.508 -0.9398)
			(stroke
				(width 0)
				(type default)
			)
			(fill no)
			(layer "F.Fab")
		)
		(pad "1" smd custom
			(at 0 -0.4445 90)
			(size 0.1397 0.1397)
			(layers "F.Cu" "F.Mask" "F.Paste")
			(net "BMC_MBC_I2C_E_SDA")
			(options
				(clearance outline)
				(anchor circle)
			)
			(primitives
				(gr_poly
					(pts
						(arc
							(start -0.1778 -0.2794)
							(mid -0.249642 -0.249642)
							(end -0.2794 -0.1778)
						)
						(arc
							(start -0.2794 0.1778)
							(mid -0.249642 0.249642)
							(end -0.1778 0.2794)
						)
						(arc
							(start 0.1778 0.2794)
							(mid 0.249642 0.249642)
							(end 0.2794 0.1778)
						)
						(arc
							(start 0.2794 -0.1778)
							(mid 0.249642 -0.249642)
							(end 0.1778 -0.2794)
						)
					)
					(width 0)
					(fill yes)
				)
			)
		)
		(pad "2" smd custom
			(at 0 0.4445 90)
			(size 0.1397 0.1397)
			(layers "F.Cu" "F.Mask" "F.Paste")
			(net "BMC0_SMB1_DAT")
			(options
				(clearance outline)
				(anchor circle)
			)
			(primitives
				(gr_poly
					(pts
						(arc
							(start -0.1778 -0.2794)
							(mid -0.249642 -0.249642)
							(end -0.2794 -0.1778)
						)
						(arc
							(start -0.2794 0.1778)
							(mid -0.249642 0.249642)
							(end -0.1778 0.2794)
						)
						(arc
							(start 0.1778 0.2794)
							(mid 0.249642 0.249642)
							(end 0.2794 0.1778)
						)
						(arc
							(start 0.2794 -0.1778)
							(mid 0.249642 -0.249642)
							(end 0.1778 -0.2794)
						)
					)
					(width 0)
					(fill yes)
				)
			)
		)
	)
	(footprint ""
		(layer "F.Cu")
		(at 86.49716 -40.259 -90)
		(property "Reference" "SC895"
			(at 0 0 270)
			(layer "F.SilkS")
			(hide yes)
			(effects
				(font
					(size 1.27 1.27)
				)
			)
		)
		(property "Value" "SCD01U10V1KX-GP"
			(at -2.8321 -1.7399 270)
			(unlocked yes)
			(layer "F.Fab")
			(hide yes)
			(effects
				(font
					(size 1.016 1.016)
					(thickness 0.1524)
				)
			)
		)
		(property "Device Type" "C0201H13"
			(at -2.8321 -3.2639 270)
			(unlocked yes)
			(layer "F.Fab")
			(hide yes)
			(effects
				(font
					(size 1.016 1.016)
					(thickness 0.1524)
				)
			)
		)
		(duplicate_pad_numbers_are_jumpers no)
		(fp_rect
			(start -0.2794 0.6477)
			(end 0.2794 -0.6477)
			(stroke
				(width 0)
				(type default)
			)
			(fill no)
			(layer "F.CrtYd")
		)
		(fp_rect
			(start -0.2794 0.6477)
			(end 0.2794 -0.6477)
			(stroke
				(width 0)
				(type default)
			)
			(fill no)
			(layer "F.Fab")
		)
		(pad "1" smd custom
			(at 0 -0.2794 270)
			(size 0.0762 0.0762)
			(layers "F.Cu" "F.Mask" "F.Paste")
			(net "SAS3008_RAID_TX_C_P7")
			(options
				(clearance outline)
				(anchor circle)
			)
			(primitives
				(gr_poly
					(pts
						(arc
							(start 0.1524 -0.127)
							(mid 0.137521 -0.162921)
							(end 0.1016 -0.1778)
						)
						(arc
							(start -0.1016 -0.1778)
							(mid -0.137521 -0.162921)
							(end -0.1524 -0.127)
						)
						(arc
							(start -0.1524 0.127)
							(mid -0.137521 0.162921)
							(end -0.1016 0.1778)
						)
						(arc
							(start 0.1016 0.1778)
							(mid 0.137521 0.162921)
							(end 0.1524 0.127)
						)
					)
					(width 0)
					(fill yes)
				)
			)
		)
		(pad "2" smd custom
			(at 0 0.2794 270)
			(size 0.0762 0.0762)
			(layers "F.Cu" "F.Mask" "F.Paste")
			(net "IOC_RAID_TX_P7")
			(options
				(clearance outline)
				(anchor circle)
			)
			(primitives
				(gr_poly
					(pts
						(arc
							(start 0.1524 -0.127)
							(mid 0.137521 -0.162921)
							(end 0.1016 -0.1778)
						)
						(arc
							(start -0.1016 -0.1778)
							(mid -0.137521 -0.162921)
							(end -0.1524 -0.127)
						)
						(arc
							(start -0.1524 0.127)
							(mid -0.137521 0.162921)
							(end -0.1016 0.1778)
						)
						(arc
							(start 0.1016 0.1778)
							(mid 0.137521 0.162921)
							(end 0.1524 0.127)
						)
					)
					(width 0)
					(fill yes)
				)
			)
		)
	)
)
